FILE_TYPE=LIBRARY_PARTS;
TIME=' COMPILATION ON MON JUL 05 19:34:43 2010  ';
PRIMITIVE 'NC7SB3157';
  PIN
    'B1':
      PIN_NUMBER='(1)';
      INPUT_LOAD='(-0.01,0.01)';
      OUTPUT_LOAD='(1.0,-1.0)';
      BIDIRECTIONAL='TRUE';
    'GND':
      PIN_NUMBER='(2)';
      PINUSE='POWER';
    'B0':
      PIN_NUMBER='(3)';
      INPUT_LOAD='(-0.01,0.01)';
      OUTPUT_LOAD='(1.0,-1.0)';
      BIDIRECTIONAL='TRUE';
    'S':
      PIN_NUMBER='(6)';
      INPUT_LOAD='(-0.01,0.01)';
    'VCC':
      PIN_NUMBER='(5)';
      PINUSE='POWER';
    'A':
      PIN_NUMBER='(4)';
      INPUT_LOAD='(-0.01,0.01)';
      OUTPUT_LOAD='(1.0,-1.0)';
      BIDIRECTIONAL='TRUE';
  END_PIN;
  BODY
    PHYS_DES_PREFIX='U';
    CLASS='IC';
    PART_NAME='NC7SB3157';
    BODY_NAME='nc7sb3157';
  END_BODY;
END_PRIMITIVE;
END.
